# S9S_MB_2U (Grand Teton) — schematic netlist excerpt (pin names and nets, part order shuffled) for the footprints in the layout excerpt that follows; sources: Cadence DE-HDL packaged netlist, KiCad conversion of 03242023_DA0F0TMBIJ0_F0T_Motherboard_J_brd_V01_OCP.brd

PC1209_P1_4  Q_CAP  22UF 4V 20% X6S  pkg C0805  page 290 : A = PVCCFA_EHV_FIVRA_CPU1 ; B = GND
L3  Q_INDUCTOR  BLM18SG331TN1D/1.5A IND  pkg SMLF  page 206 : \1\ = P3V3 ; \2\ = P3V3_DB2000_VDD

(kicad_pcb
	(version 20260206)
	(generator "pcbnew")
	(generator_version "10.0")
	(general
		(thickness 1.6)
		(legacy_teardrops no)
	)
	(paper "A4")
	(title_block
		(title "03242023_DA0F0TMBIJ0_F0T_Motherboard_J_brd_V01_OCP.brd")
		(comment 1 "Grand Teton / footprints 5689-5690 of 6105")
	)
	(layers
		(0 "F.Cu" signal "TOP")
		(4 "In1.Cu" signal "GND")
		(6 "In2.Cu" signal "IN1")
		(8 "In3.Cu" signal "GND1")
		(10 "In4.Cu" signal "IN2")
		(12 "In5.Cu" signal "GND2")
		(14 "In6.Cu" signal "IN3")
		(16 "In7.Cu" signal "GND3")
		(18 "In8.Cu" signal "VCC")
		(20 "In9.Cu" signal "VCC1")
		(22 "In10.Cu" signal "GND4")
		(24 "In11.Cu" signal "IN4")
		(26 "In12.Cu" signal "GND5")
		(28 "In13.Cu" signal "IN5")
		(30 "In14.Cu" signal "GND6")
		(32 "In15.Cu" signal "IN6")
		(34 "In16.Cu" signal "GND7")
		(2 "B.Cu" signal "BOTTOM")
		(9 "F.Adhes" user "F.Adhesive")
		(11 "B.Adhes" user "B.Adhesive")
		(13 "F.Paste" user "Package Geometry/Pastemask Top")
		(15 "B.Paste" user "Package Geometry/Pastemask Bottom")
		(5 "F.SilkS" user "Ref Des/Silkscreen Top")
		(7 "B.SilkS" user "Ref Des/Silkscreen Bottom")
		(1 "F.Mask" user "Board Geometry/Soldermask Top")
		(3 "B.Mask" user "Board Geometry/Soldermask Bottom")
		(17 "Dwgs.User" user "User.Drawings")
		(19 "Cmts.User" user "User.Comments")
		(21 "Eco1.User" user "User.Eco1")
		(23 "Eco2.User" user "User.Eco2")
		(25 "Edge.Cuts" user "Board Geometry/Outline")
		(27 "Margin" user)
		(31 "F.CrtYd" user "Package Geometry/Place Bound Top")
		(29 "B.CrtYd" user "Package Geometry/Place Bound Bottom")
		(35 "F.Fab" user "Ref Des/Assembly Top")
		(33 "B.Fab" user "Ref Des/Assembly Bottom")
	)
	(footprint ""
		(layer "B.Cu")
		(at 38.015926 -344.935556 -90)
		(property "Reference" "PC1209_P1_4"
			(at 0 0 90)
			(layer "B.SilkS")
			(hide yes)
			(effects
				(font
					(size 1.27 1.27)
				)
				(justify mirror)
			)
		)
		(property "Value" ""
			(at 0 0 90)
			(layer "B.Fab")
			(effects
				(font
					(size 1.27 1.27)
				)
				(justify mirror)
			)
		)
		(duplicate_pad_numbers_are_jumpers no)
		(fp_line
			(start -1.524 0.762)
			(end 1.524 0.762)
			(stroke
				(width 0.1524)
				(type default)
			)
			(layer "B.SilkS")
		)
		(fp_line
			(start 1.524 0.762)
			(end 1.524 -0.762)
			(stroke
				(width 0.1524)
				(type default)
			)
			(layer "B.SilkS")
		)
		(fp_line
			(start -1.524 -0.762)
			(end -1.524 0.762)
			(stroke
				(width 0.1524)
				(type default)
			)
			(layer "B.SilkS")
		)
		(fp_line
			(start 1.524 -0.762)
			(end -1.524 -0.762)
			(stroke
				(width 0.1524)
				(type default)
			)
			(layer "B.SilkS")
		)
		(fp_line
			(start -1.1049 0.724916)
			(end -1.1049 -0.724916)
			(stroke
				(width 0.1)
				(type default)
			)
			(layer "B.Fab")
		)
		(fp_line
			(start 1.1049 0.724916)
			(end -1.1049 0.724916)
			(stroke
				(width 0.1)
				(type default)
			)
			(layer "B.Fab")
		)
		(fp_line
			(start -1.1049 -0.724916)
			(end 1.1049 -0.724916)
			(stroke
				(width 0.1)
				(type default)
			)
			(layer "B.Fab")
		)
		(fp_line
			(start 1.1049 -0.724916)
			(end 1.1049 0.724916)
			(stroke
				(width 0.1)
				(type default)
			)
			(layer "B.Fab")
		)
		(pad "1" smd rect
			(at 0.889 0 270)
			(size 1.016 1.27)
			(layers "B.Cu" "B.Mask" "B.Paste")
			(net "PVCCFA_EHV_FIVRA_CPU1")
		)
		(pad "2" smd rect
			(at -0.889 0 270)
			(size 1.016 1.27)
			(layers "B.Cu" "B.Mask" "B.Paste")
			(net "GND")
		)
	)
	(footprint ""
		(layer "B.Cu")
		(at 230.249222 -121.743216 -90)
		(property "Reference" "L3"
			(at 0 0 90)
			(layer "B.SilkS")
			(hide yes)
			(effects
				(font
					(size 1.27 1.27)
				)
				(justify mirror)
			)
		)
		(property "Value" ""
			(at 0 0 90)
			(layer "B.Fab")
			(effects
				(font
					(size 1.27 1.27)
				)
				(justify mirror)
			)
		)
		(duplicate_pad_numbers_are_jumpers no)
		(fp_line
			(start -1.27 0.5842)
			(end 1.27 0.5842)
			(stroke
				(width 0.1524)
				(type default)
			)
			(layer "B.SilkS")
		)
		(fp_line
			(start -1.27 0.5842)
			(end -1.27 -0.5842)
			(stroke
				(width 0.1524)
				(type default)
			)
			(layer "B.SilkS")
		)
		(fp_line
			(start -0.127 0.5842)
			(end -0.127 -0.5842)
			(stroke
				(width 0.1524)
				(type default)
			)
			(layer "B.SilkS")
		)
		(fp_line
			(start 0.127 0.5842)
			(end 0.127 -0.5842)
			(stroke
				(width 0.1524)
				(type default)
			)
			(layer "B.SilkS")
		)
		(fp_line
			(start 1.27 0.5842)
			(end 1.27 -0.5842)
			(stroke
				(width 0.1524)
				(type default)
			)
			(layer "B.SilkS")
		)
		(fp_line
			(start 1.27 -0.5588)
			(end 1.27 -0.5842)
			(stroke
				(width 0.1524)
				(type default)
			)
			(layer "B.SilkS")
		)
		(fp_line
			(start 1.27 -0.5842)
			(end -1.27 -0.5842)
			(stroke
				(width 0.1524)
				(type default)
			)
			(layer "B.SilkS")
		)
		(fp_line
			(start -0.9144 0.508)
			(end 0.9144 0.508)
			(stroke
				(width 0.1)
				(type default)
			)
			(layer "B.Fab")
		)
		(fp_line
			(start 0.9144 0.508)
			(end 0.9144 0.406654)
			(stroke
				(width 0.1)
				(type default)
			)
			(layer "B.Fab")
		)
		(fp_line
			(start 0.9144 0.406654)
			(end 1.194308 0.406654)
			(stroke
				(width 0.1)
				(type default)
			)
			(layer "B.Fab")
		)
		(fp_line
			(start 1.194308 0.406654)
			(end 1.194308 -0.406654)
			(stroke
				(width 0.1)
				(type default)
			)
			(layer "B.Fab")
		)
		(fp_line
			(start -1.1938 0.4064)
			(end -0.9144 0.4064)
			(stroke
				(width 0.1)
				(type default)
			)
			(layer "B.Fab")
		)
		(fp_line
			(start -0.9144 0.4064)
			(end -0.9144 0.508)
			(stroke
				(width 0.1)
				(type default)
			)
			(layer "B.Fab")
		)
		(fp_line
			(start -1.1938 -0.406654)
			(end -1.1938 0.4064)
			(stroke
				(width 0.1)
				(type default)
			)
			(layer "B.Fab")
		)
		(fp_line
			(start -0.9144 -0.406654)
			(end -1.1938 -0.406654)
			(stroke
				(width 0.1)
				(type default)
			)
			(layer "B.Fab")
		)
		(fp_line
			(start 0.9144 -0.406654)
			(end 0.9144 -0.508)
			(stroke
				(width 0.1)
				(type default)
			)
			(layer "B.Fab")
		)
		(fp_line
			(start 1.194308 -0.406654)
			(end 0.9144 -0.406654)
			(stroke
				(width 0.1)
				(type default)
			)
			(layer "B.Fab")
		)
		(fp_line
			(start -0.9144 -0.508)
			(end -0.9144 -0.406654)
			(stroke
				(width 0.1)
				(type default)
			)
			(layer "B.Fab")
		)
		(fp_line
			(start 0.9144 -0.508)
			(end -0.9144 -0.508)
			(stroke
				(width 0.1)
				(type default)
			)
			(layer "B.Fab")
		)
		(pad "1" smd rect
			(at 0.7366 0 180)
			(size 0.7112 0.8128)
			(layers "B.Cu" "B.Mask" "B.Paste")
			(net "P3V3")
		)
		(pad "2" smd rect
			(at -0.7366 0 180)
			(size 0.7112 0.8128)
			(layers "B.Cu" "B.Mask" "B.Paste")
			(net "P3V3_DB2000_VDD")
		)
	)
)
